(kicad_pcb
	(version 20241229)
	(generator "pcbnew")
	(generator_version "9.0")
	(general
		(thickness 1.294)
		(legacy_teardrops no)
	)
	(paper "A3")
	(title_block
		(title "Kintex 410T devboard")
		(date "2024-04-03")
		(rev "1.1.2")
		(comment 9 "footprints 667-672 of 975")
	)
	(layers
		(0 "F.Cu" mixed)
		(4 "In1.Cu" power)
		(6 "In2.Cu" power)
		(8 "In3.Cu" mixed)
		(10 "In4.Cu" power)
		(12 "In5.Cu" mixed)
		(14 "In6.Cu" power)
		(16 "In7.Cu" mixed)
		(18 "In8.Cu" power)
		(2 "B.Cu" mixed)
		(9 "F.Adhes" user "F.Adhesive")
		(11 "B.Adhes" user "B.Adhesive")
		(13 "F.Paste" user)
		(15 "B.Paste" user)
		(5 "F.SilkS" user "F.Silkscreen")
		(7 "B.SilkS" user "B.Silkscreen")
		(1 "F.Mask" user)
		(3 "B.Mask" user)
		(17 "Dwgs.User" user "User.Drawings")
		(19 "Cmts.User" user "User.Comments")
		(21 "Eco1.User" user "User.Eco1")
		(23 "Eco2.User" user "User.Eco2")
		(25 "Edge.Cuts" user)
		(27 "Margin" user)
		(31 "F.CrtYd" user "F.Courtyard")
		(29 "B.CrtYd" user "B.Courtyard")
		(35 "F.Fab" user)
		(33 "B.Fab" user)
	)
	(footprint "antmicro-footprints:C_0201"
		(layer "B.Cu")
		(at 188.000001 126.500001 180)
		(descr "Capacitor SMD 0201")
		(tags "capacitor SMD 0201")
		(property "Reference" "C145"
			(at 0.525001 -0.424999 0)
			(layer "B.SilkS")
			(effects
				(font
					(size 0.7 0.7)
					(thickness 0.15)
				)
				(justify left bottom mirror)
			)
		)
		(property "Value" "C_100n_0201"
			(at 0 -1.4 0)
			(layer "B.Fab")
			(effects
				(font
					(size 0.7 0.7)
					(thickness 0.15)
				)
				(justify left bottom mirror)
			)
		)
		(property "Description" "SMD Multilayer Ceramic Capacitor, 0.1 µF, 6.3 V, 0201 [0603 Metric], ± 10%, X6S, CC Series"
			(at 0 0 180)
			(layer "F.Fab")
			(hide yes)
			(effects
				(font
					(size 1.27 1.27)
					(thickness 0.15)
				)
			)
		)
		(property "Author" "Antmicro"
			(at 376.000002 253.000002 0)
			(layer "B.Fab")
			(hide yes)
			(effects
				(font
					(size 1 1)
					(thickness 0.15)
				)
				(justify mirror)
			)
		)
		(property "Dielectric" ""
			(at 376.000002 253.000002 0)
			(layer "B.Fab")
			(hide yes)
			(effects
				(font
					(size 1 1)
					(thickness 0.15)
				)
				(justify mirror)
			)
		)
		(property "License" "Apache-2.0"
			(at 376.000002 253.000002 0)
			(layer "B.Fab")
			(hide yes)
			(effects
				(font
					(size 1 1)
					(thickness 0.15)
				)
				(justify mirror)
			)
		)
		(property "MPN" "CC0201KRX6S5BB104"
			(at 376.000002 253.000002 0)
			(layer "B.Fab")
			(hide yes)
			(effects
				(font
					(size 1 1)
					(thickness 0.15)
				)
				(justify mirror)
			)
		)
		(property "Manufacturer" "YAGEO"
			(at 376.000002 253.000002 0)
			(layer "B.Fab")
			(hide yes)
			(effects
				(font
					(size 1 1)
					(thickness 0.15)
				)
				(justify mirror)
			)
		)
		(property "Val" "100n"
			(at 376.000002 253.000002 0)
			(layer "B.Fab")
			(hide yes)
			(effects
				(font
					(size 1 1)
					(thickness 0.15)
				)
				(justify mirror)
			)
		)
		(property "Voltage" ""
			(at 376.000002 253.000002 0)
			(layer "B.Fab")
			(hide yes)
			(effects
				(font
					(size 1 1)
					(thickness 0.15)
				)
				(justify mirror)
			)
		)
		(sheetname "FPGA supply")
		(sheetfile "fpga-supply.kicad_sch")
		(attr smd)
		(fp_rect
			(start -0.7 0.35)
			(end 0.7 -0.35)
			(stroke
				(width 0.05)
				(type default)
			)
			(fill no)
			(layer "B.CrtYd")
		)
		(fp_rect
			(start 0.3 -0.15)
			(end -0.301 0.149)
			(stroke
				(width 0.15)
				(type solid)
			)
			(fill no)
			(layer "B.Fab")
		)
		(pad "" smd roundrect
			(at -0.349 0.002 180)
			(size 0.318 0.36)
			(layers "B.Paste")
			(roundrect_rratio 0.25)
		)
		(pad "" smd roundrect
			(at 0.341 0.002 180)
			(size 0.318 0.36)
			(layers "B.Paste")
			(roundrect_rratio 0.25)
		)
		(pad "1" smd roundrect
			(at -0.321 0.002 180)
			(size 0.46 0.4)
			(layers "B.Cu" "B.Mask")
			(roundrect_rratio 0.25)
			(net 1 "GND")
			(pintype "passive")
		)
		(pad "2" smd roundrect
			(at 0.32 0.002 180)
			(size 0.46 0.4)
			(layers "B.Cu" "B.Mask")
			(roundrect_rratio 0.25)
			(net 8 "+1V2_MGTAVTT")
			(pintype "passive")
		)
	)
	(footprint "antmicro-footprints:C_0402_1005Metric"
		(layer "B.Cu")
		(at 197 119.5)
		(descr "Capacitor SMD 0402")
		(tags "capacitor SMD 0402")
		(property "Reference" "C88"
			(at 1.125 -0.5 180)
			(layer "B.SilkS")
			(effects
				(font
					(size 0.7 0.7)
					(thickness 0.15)
				)
				(justify left bottom mirror)
			)
		)
		(property "Value" "C_100n_0402"
			(at 0 -1.169 180)
			(layer "B.Fab")
			(effects
				(font
					(size 0.7 0.7)
					(thickness 0.15)
				)
				(justify left bottom mirror)
			)
		)
		(property "Description" "SMD Multilayer Ceramic Capacitor, 0.1 µF, 50 V, 0402 [1005 Metric], ± 10%, X5R, GRM Series"
			(at 0 0 0)
			(layer "F.Fab")
			(hide yes)
			(effects
				(font
					(size 1.27 1.27)
					(thickness 0.15)
				)
			)
		)
		(property "Author" "Antmicro"
			(at 0 0 0)
			(layer "B.Fab")
			(hide yes)
			(effects
				(font
					(size 1 1)
					(thickness 0.15)
				)
				(justify mirror)
			)
		)
		(property "Dielectric" "X5R"
			(at 0 0 0)
			(layer "B.Fab")
			(hide yes)
			(effects
				(font
					(size 1 1)
					(thickness 0.15)
				)
				(justify mirror)
			)
		)
		(property "License" "Apache-2.0"
			(at 0 0 0)
			(layer "B.Fab")
			(hide yes)
			(effects
				(font
					(size 1 1)
					(thickness 0.15)
				)
				(justify mirror)
			)
		)
		(property "MPN" "GRM155R61H104KE14D"
			(at 0 0 0)
			(layer "B.Fab")
			(hide yes)
			(effects
				(font
					(size 1 1)
					(thickness 0.15)
				)
				(justify mirror)
			)
		)
		(property "Manufacturer" "Murata"
			(at 0 0 0)
			(layer "B.Fab")
			(hide yes)
			(effects
				(font
					(size 1 1)
					(thickness 0.15)
				)
				(justify mirror)
			)
		)
		(property "Val" "100n"
			(at 0 0 0)
			(layer "B.Fab")
			(hide yes)
			(effects
				(font
					(size 1 1)
					(thickness 0.15)
				)
				(justify mirror)
			)
		)
		(property "Voltage" "50V"
			(at 0 0 0)
			(layer "B.Fab")
			(hide yes)
			(effects
				(font
					(size 1 1)
					(thickness 0.15)
				)
				(justify mirror)
			)
		)
		(sheetname "FPGA Bank 18 & 32")
		(sheetfile "fpga-bank-18-32.kicad_sch")
		(attr smd)
		(fp_rect
			(start -0.925 0.47)
			(end 0.925 -0.47)
			(stroke
				(width 0.05)
				(type default)
			)
			(fill no)
			(layer "B.CrtYd")
		)
		(fp_line
			(start -0.494 -0.248)
			(end -0.494 0.25)
			(stroke
				(width 0.15)
				(type solid)
			)
			(layer "B.Fab")
		)
		(fp_line
			(start -0.494 0.25)
			(end 0.504 0.25)
			(stroke
				(width 0.15)
				(type solid)
			)
			(layer "B.Fab")
		)
		(fp_line
			(start 0.504 -0.248)
			(end -0.494 -0.248)
			(stroke
				(width 0.15)
				(type solid)
			)
			(layer "B.Fab")
		)
		(fp_line
			(start 0.504 0.25)
			(end 0.504 -0.248)
			(stroke
				(width 0.15)
				(type solid)
			)
			(layer "B.Fab")
		)
		(pad "1" smd roundrect
			(at -0.48 0)
			(size 0.59 0.64)
			(layers "B.Cu" "B.Mask" "B.Paste")
			(roundrect_rratio 0.25)
			(net 1 "GND")
			(pintype "passive")
		)
		(pad "2" smd roundrect
			(at 0.48 0)
			(size 0.59 0.64)
			(layers "B.Cu" "B.Mask" "B.Paste")
			(roundrect_rratio 0.25)
			(net 24 "+3V3")
			(pintype "passive")
		)
	)
	(footprint "antmicro-footprints:R_0402_1005Metric"
		(layer "B.Cu")
		(at 233.8 148.9)
		(descr "Resistor SMD 0402")
		(tags "resistor SMD 0402")
		(property "Reference" "R195"
			(at -0.7 0.375 180)
			(layer "B.SilkS")
			(effects
				(font
					(size 0.7 0.7)
					(thickness 0.15)
				)
				(justify left bottom mirror)
			)
		)
		(property "Value" "R_10k_0402"
			(at 0 -1.4 180)
			(layer "B.Fab")
			(effects
				(font
					(size 0.7 0.7)
					(thickness 0.15)
				)
				(justify left bottom mirror)
			)
		)
		(property "Description" "SMD Chip Resistor, 10 kohm, ± 1%, 62.5 mW, 0402 [1005 Metric], Thick Film, General Purpose"
			(at 0 0 0)
			(layer "F.Fab")
			(hide yes)
			(effects
				(font
					(size 1.27 1.27)
					(thickness 0.15)
				)
			)
		)
		(property "Author" "Antmicro"
			(at 0 0 0)
			(layer "B.Fab")
			(hide yes)
			(effects
				(font
					(size 1 1)
					(thickness 0.15)
				)
				(justify mirror)
			)
		)
		(property "License" "Apache-2.0"
			(at 0 0 0)
			(layer "B.Fab")
			(hide yes)
			(effects
				(font
					(size 1 1)
					(thickness 0.15)
				)
				(justify mirror)
			)
		)
		(property "MPN" "CR0402-FX-1002GLF"
			(at 0 0 0)
			(layer "B.Fab")
			(hide yes)
			(effects
				(font
					(size 1 1)
					(thickness 0.15)
				)
				(justify mirror)
			)
		)
		(property "Manufacturer" "Bourns"
			(at 0 0 0)
			(layer "B.Fab")
			(hide yes)
			(effects
				(font
					(size 1 1)
					(thickness 0.15)
				)
				(justify mirror)
			)
		)
		(property "Tolerance" "1%"
			(at 0 0 0)
			(layer "B.Fab")
			(hide yes)
			(effects
				(font
					(size 1 1)
					(thickness 0.15)
				)
				(justify mirror)
			)
		)
		(property "Val" "10k"
			(at 0 0 0)
			(layer "B.Fab")
			(hide yes)
			(effects
				(font
					(size 1 1)
					(thickness 0.15)
				)
				(justify mirror)
			)
		)
		(sheetname "USB PHY")
		(sheetfile "usb-phy.kicad_sch")
		(attr smd)
		(fp_rect
			(start -0.925 0.47)
			(end 0.925 -0.47)
			(stroke
				(width 0.05)
				(type default)
			)
			(fill no)
			(layer "B.CrtYd")
		)
		(fp_rect
			(start -0.5 0.25)
			(end 0.5 -0.25)
			(stroke
				(width 0.15)
				(type solid)
			)
			(fill no)
			(layer "B.Fab")
		)
		(pad "1" smd roundrect
			(at -0.48 0)
			(size 0.59 0.64)
			(layers "B.Cu" "B.Mask" "B.Paste")
			(roundrect_rratio 0.25)
			(net 500 "/FPGA Bank 12 & 13/USB_USER.SUS")
			(pintype "passive")
		)
		(pad "2" smd roundrect
			(at 0.48 0)
			(size 0.59 0.64)
			(layers "B.Cu" "B.Mask" "B.Paste")
			(roundrect_rratio 0.25)
			(net 26 "+1V8")
			(pintype "passive")
		)
	)
	(footprint "antmicro-footprints:C_0402_1005Metric"
		(layer "B.Cu")
		(at 205 141.5)
		(descr "Capacitor SMD 0402")
		(tags "capacitor SMD 0402")
		(property "Reference" "C17"
			(at 1.1 -0.425 180)
			(layer "B.SilkS")
			(effects
				(font
					(size 0.7 0.7)
					(thickness 0.15)
				)
				(justify left bottom mirror)
			)
		)
		(property "Value" "C_100n_0402"
			(at 0 -1.169 180)
			(layer "B.Fab")
			(effects
				(font
					(size 0.7 0.7)
					(thickness 0.15)
				)
				(justify left bottom mirror)
			)
		)
		(property "Description" "SMD Multilayer Ceramic Capacitor, 0.1 µF, 50 V, 0402 [1005 Metric], ± 10%, X5R, GRM Series"
			(at 0 0 0)
			(layer "F.Fab")
			(hide yes)
			(effects
				(font
					(size 1.27 1.27)
					(thickness 0.15)
				)
			)
		)
		(property "Author" "Antmicro"
			(at 0 0 0)
			(layer "B.Fab")
			(hide yes)
			(effects
				(font
					(size 1 1)
					(thickness 0.15)
				)
				(justify mirror)
			)
		)
		(property "Dielectric" "X5R"
			(at 0 0 0)
			(layer "B.Fab")
			(hide yes)
			(effects
				(font
					(size 1 1)
					(thickness 0.15)
				)
				(justify mirror)
			)
		)
		(property "License" "Apache-2.0"
			(at 0 0 0)
			(layer "B.Fab")
			(hide yes)
			(effects
				(font
					(size 1 1)
					(thickness 0.15)
				)
				(justify mirror)
			)
		)
		(property "MPN" "GRM155R61H104KE14D"
			(at 0 0 0)
			(layer "B.Fab")
			(hide yes)
			(effects
				(font
					(size 1 1)
					(thickness 0.15)
				)
				(justify mirror)
			)
		)
		(property "Manufacturer" "Murata"
			(at 0 0 0)
			(layer "B.Fab")
			(hide yes)
			(effects
				(font
					(size 1 1)
					(thickness 0.15)
				)
				(justify mirror)
			)
		)
		(property "Val" "100n"
			(at 0 0 0)
			(layer "B.Fab")
			(hide yes)
			(effects
				(font
					(size 1 1)
					(thickness 0.15)
				)
				(justify mirror)
			)
		)
		(property "Voltage" "50V"
			(at 0 0 0)
			(layer "B.Fab")
			(hide yes)
			(effects
				(font
					(size 1 1)
					(thickness 0.15)
				)
				(justify mirror)
			)
		)
		(sheetname "FPGA Bank 12 & 13")
		(sheetfile "fpga-bank-12-13.kicad_sch")
		(attr smd)
		(fp_rect
			(start -0.925 0.47)
			(end 0.925 -0.47)
			(stroke
				(width 0.05)
				(type default)
			)
			(fill no)
			(layer "B.CrtYd")
		)
		(fp_line
			(start -0.494 -0.248)
			(end -0.494 0.25)
			(stroke
				(width 0.15)
				(type solid)
			)
			(layer "B.Fab")
		)
		(fp_line
			(start -0.494 0.25)
			(end 0.504 0.25)
			(stroke
				(width 0.15)
				(type solid)
			)
			(layer "B.Fab")
		)
		(fp_line
			(start 0.504 -0.248)
			(end -0.494 -0.248)
			(stroke
				(width 0.15)
				(type solid)
			)
			(layer "B.Fab")
		)
		(fp_line
			(start 0.504 0.25)
			(end 0.504 -0.248)
			(stroke
				(width 0.15)
				(type solid)
			)
			(layer "B.Fab")
		)
		(pad "1" smd roundrect
			(at -0.48 0)
			(size 0.59 0.64)
			(layers "B.Cu" "B.Mask" "B.Paste")
			(roundrect_rratio 0.25)
			(net 1 "GND")
			(pintype "passive")
		)
		(pad "2" smd roundrect
			(at 0.48 0)
			(size 0.59 0.64)
			(layers "B.Cu" "B.Mask" "B.Paste")
			(roundrect_rratio 0.25)
			(net 24 "+3V3")
			(pintype "passive")
		)
	)
	(footprint "antmicro-footprints:R_0603_1608Metric"
		(layer "B.Cu")
		(at 262.401 152.5 180)
		(descr "Resistor SMD 0603")
		(tags "resistor SMD 0603")
		(property "Reference" "R252"
			(at -1.374 0.55 0)
			(layer "B.SilkS")
			(effects
				(font
					(size 0.7 0.7)
					(thickness 0.15)
				)
				(justify left bottom mirror)
			)
		)
		(property "Value" "R_220R_0603"
			(at 0 -1.6 0)
			(layer "B.Fab")
			(effects
				(font
					(size 0.7 0.7)
					(thickness 0.15)
				)
				(justify left bottom mirror)
			)
		)
		(property "Description" "SMD Chip Resistor, 220 ohm, ± 1%, 100 mW, 0603 [1608 Metric], Thick Film, General Purpose"
			(at 0 0 180)
			(layer "F.Fab")
			(hide yes)
			(effects
				(font
					(size 1.27 1.27)
					(thickness 0.15)
				)
			)
		)
		(property "Author" "Antmicro"
			(at 524.802 305 0)
			(layer "B.Fab")
			(hide yes)
			(effects
				(font
					(size 1 1)
					(thickness 0.15)
				)
				(justify mirror)
			)
		)
		(property "License" "Apache-2.0"
			(at 524.802 305 0)
			(layer "B.Fab")
			(hide yes)
			(effects
				(font
					(size 1 1)
					(thickness 0.15)
				)
				(justify mirror)
			)
		)
		(property "MPN" "CR0603-FX-2200ELF"
			(at 524.802 305 0)
			(layer "B.Fab")
			(hide yes)
			(effects
				(font
					(size 1 1)
					(thickness 0.15)
				)
				(justify mirror)
			)
		)
		(property "Manufacturer" "Bourns"
			(at 524.802 305 0)
			(layer "B.Fab")
			(hide yes)
			(effects
				(font
					(size 1 1)
					(thickness 0.15)
				)
				(justify mirror)
			)
		)
		(property "Tolerance" "1%"
			(at 524.802 305 0)
			(layer "B.Fab")
			(hide yes)
			(effects
				(font
					(size 1 1)
					(thickness 0.15)
				)
				(justify mirror)
			)
		)
		(property "Val" "220R"
			(at 524.802 305 0)
			(layer "B.Fab")
			(hide yes)
			(effects
				(font
					(size 1 1)
					(thickness 0.15)
				)
				(justify mirror)
			)
		)
		(sheetname "HDMI + Ethernet")
		(sheetfile "hdmi-ethernet.kicad_sch")
		(attr smd)
		(fp_line
			(start -0.15 0.4)
			(end 0.15 0.4)
			(stroke
				(width 0.15)
				(type solid)
			)
			(layer "B.SilkS")
		)
		(fp_line
			(start -0.15 -0.4)
			(end 0.15 -0.4)
			(stroke
				(width 0.15)
				(type solid)
			)
			(layer "B.SilkS")
		)
		(fp_rect
			(start -1.25 0.65)
			(end 1.25 -0.65)
			(stroke
				(width 0.05)
				(type solid)
			)
			(fill no)
			(layer "B.CrtYd")
		)
		(fp_rect
			(start -0.8 0.4)
			(end 0.8 -0.4)
			(stroke
				(width 0.15)
				(type solid)
			)
			(fill no)
			(layer "B.Fab")
		)
		(pad "1" smd roundrect
			(at -0.7 0 180)
			(size 0.8 1)
			(layers "B.Cu" "B.Mask" "B.Paste")
			(roundrect_rratio 0.2)
			(net 848 "/HDMI + Ethernet/ETH_LED_SPD+")
			(pintype "passive")
		)
		(pad "2" smd roundrect
			(at 0.7 0 180)
			(size 0.8 1)
			(layers "B.Cu" "B.Mask" "B.Paste")
			(roundrect_rratio 0.2)
			(net 24 "+3V3")
			(pintype "passive")
		)
	)
	(footprint "antmicro-footprints:R_0402_1005Metric"
		(layer "B.Cu")
		(at 191.9 84.8 90)
		(descr "Resistor SMD 0402")
		(tags "resistor SMD 0402")
		(property "Reference" "R138"
			(at -0.725 0.4 270)
			(layer "B.SilkS")
			(effects
				(font
					(size 0.7 0.7)
					(thickness 0.15)
				)
				(justify left bottom mirror)
			)
		)
		(property "Value" "R_100R_0402"
			(at 0 -1.4 270)
			(layer "B.Fab")
			(effects
				(font
					(size 0.7 0.7)
					(thickness 0.15)
				)
				(justify left bottom mirror)
			)
		)
		(property "Description" "SMD Chip Resistor, 100 ohm, ± 1%, 62.5 mW, 0402 [1005 Metric], Thick Film, General Purpose"
			(at 0 0 90)
			(layer "F.Fab")
			(hide yes)
			(effects
				(font
					(size 1.27 1.27)
					(thickness 0.15)
				)
			)
		)
		(property "Author" "Antmicro"
			(at 276.7 -107.1 0)
			(layer "B.Fab")
			(hide yes)
			(effects
				(font
					(size 1 1)
					(thickness 0.15)
				)
				(justify mirror)
			)
		)
		(property "License" "Apache-2.0"
			(at 276.7 -107.1 0)
			(layer "B.Fab")
			(hide yes)
			(effects
				(font
					(size 1 1)
					(thickness 0.15)
				)
				(justify mirror)
			)
		)
		(property "MPN" "CR0402-FX-1000GLF"
			(at 276.7 -107.1 0)
			(layer "B.Fab")
			(hide yes)
			(effects
				(font
					(size 1 1)
					(thickness 0.15)
				)
				(justify mirror)
			)
		)
		(property "Manufacturer" "Bourns"
			(at 276.7 -107.1 0)
			(layer "B.Fab")
			(hide yes)
			(effects
				(font
					(size 1 1)
					(thickness 0.15)
				)
				(justify mirror)
			)
		)
		(property "Tolerance" "1%"
			(at 276.7 -107.1 0)
			(layer "B.Fab")
			(hide yes)
			(effects
				(font
					(size 1 1)
					(thickness 0.15)
				)
				(justify mirror)
			)
		)
		(property "Val" "100R"
			(at 276.7 -107.1 0)
			(layer "B.Fab")
			(hide yes)
			(effects
				(font
					(size 1 1)
					(thickness 0.15)
				)
				(justify mirror)
			)
		)
		(sheetname "User GPIO + LED + button + DIP switch")
		(sheetfile "user-gpio.kicad_sch")
		(attr smd)
		(fp_rect
			(start -0.925 0.47)
			(end 0.925 -0.47)
			(stroke
				(width 0.05)
				(type default)
			)
			(fill no)
			(layer "B.CrtYd")
		)
		(fp_rect
			(start -0.5 0.25)
			(end 0.5 -0.25)
			(stroke
				(width 0.15)
				(type solid)
			)
			(fill no)
			(layer "B.Fab")
		)
		(pad "1" smd roundrect
			(at -0.48 0 90)
			(size 0.59 0.64)
			(layers "B.Cu" "B.Mask" "B.Paste")
			(roundrect_rratio 0.25)
			(net 830 "/User GPIO + LED + button + DIP switch/CW_20PIN_TPDIC")
			(pintype "passive")
		)
		(pad "2" smd roundrect
			(at 0.48 0 90)
			(size 0.59 0.64)
			(layers "B.Cu" "B.Mask" "B.Paste")
			(roundrect_rratio 0.25)
			(net 480 "/FPGA Bank 12 & 13/CW_HEADER.TPDIC")
			(pintype "passive")
		)
	)
)
